(kicad_pcb
	(version 20260206)
	(generator "pcbnew")
	(generator_version "10.0")
	(general
		(thickness 1.6)
		(legacy_teardrops no)
	)
	(paper "A4")
	(title_block
		(title "fcb — Lightning_FCB_BRD.brd")
		(comment 1 "Lightning (Wiwynn / Facebook NVMe JBOF) / footprints 17-24 of 495")
	)
	(layers
		(0 "F.Cu" signal "TOP")
		(4 "In1.Cu" signal "L2GND")
		(6 "In2.Cu" signal "L3VCC")
		(2 "B.Cu" signal "BOTTOM")
		(9 "F.Adhes" user "F.Adhesive")
		(11 "B.Adhes" user "B.Adhesive")
		(13 "F.Paste" user "Package Geometry/Pastemask Top")
		(15 "B.Paste" user "Package Geometry/Pastemask Bottom")
		(5 "F.SilkS" user "Ref Des/Silkscreen Top")
		(7 "B.SilkS" user "Ref Des/Silkscreen Bottom")
		(1 "F.Mask" user "Board Geometry/Soldermask Top")
		(3 "B.Mask" user "Board Geometry/Soldermask Bottom")
		(17 "Dwgs.User" user "User.Drawings")
		(19 "Cmts.User" user "User.Comments")
		(21 "Eco1.User" user "User.Eco1")
		(23 "Eco2.User" user "User.Eco2")
		(25 "Edge.Cuts" user "Board Geometry/Outline")
		(27 "Margin" user)
		(31 "F.CrtYd" user "Package Geometry/Place Bound Top")
		(29 "B.CrtYd" user "Package Geometry/Place Bound Bottom")
		(35 "F.Fab" user "Ref Des/Assembly Top")
		(33 "B.Fab" user "Ref Des/Assembly Bottom")
	)
	(footprint ""
		(layer "F.Cu")
		(at 41.7576 -159.1818 -90)
		(property "Reference" "R15"
			(at 0 0 270)
			(layer "F.SilkS")
			(hide yes)
			(effects
				(font
					(size 1.27 1.27)
				)
			)
		)
		(property "Value" "10KR2F-2-GP"
			(at 0.064008 -3.993896 270)
			(unlocked yes)
			(layer "F.Fab")
			(hide yes)
			(effects
				(font
					(size 1.016 1.016)
					(thickness 0.1524)
				)
			)
		)
		(property "Device Type" "R402H16"
			(at 0.064008 -5.517896 270)
			(unlocked yes)
			(layer "F.Fab")
			(hide yes)
			(effects
				(font
					(size 1.016 1.016)
					(thickness 0.1524)
				)
			)
		)
		(duplicate_pad_numbers_are_jumpers no)
		(fp_line
			(start -0.508 -0.9398)
			(end -0.508 0.9398)
			(stroke
				(width 0.1524)
				(type default)
			)
			(layer "F.SilkS")
		)
		(fp_line
			(start 0.508 -0.9398)
			(end -0.508 -0.9398)
			(stroke
				(width 0.1524)
				(type default)
			)
			(layer "F.SilkS")
		)
		(fp_rect
			(start -0.508 0.9398)
			(end 0.508 -0.9398)
			(stroke
				(width 0)
				(type default)
			)
			(fill no)
			(layer "F.CrtYd")
		)
		(fp_rect
			(start -0.508 0.9398)
			(end 0.508 -0.9398)
			(stroke
				(width 0)
				(type default)
			)
			(fill no)
			(layer "F.Fab")
		)
		(pad "1" smd custom
			(at 0 -0.4445 270)
			(size 0.1397 0.1397)
			(layers "F.Cu" "F.Mask" "F.Paste")
			(net "NCT7904_VSEN_P12V_AUX")
			(options
				(clearance outline)
				(anchor circle)
			)
			(primitives
				(gr_poly
					(pts
						(arc
							(start -0.1778 -0.2794)
							(mid -0.249642 -0.249642)
							(end -0.2794 -0.1778)
						)
						(arc
							(start -0.2794 0.1778)
							(mid -0.249642 0.249642)
							(end -0.1778 0.2794)
						)
						(arc
							(start 0.1778 0.2794)
							(mid 0.249642 0.249642)
							(end 0.2794 0.1778)
						)
						(arc
							(start 0.2794 -0.1778)
							(mid 0.249642 -0.249642)
							(end 0.1778 -0.2794)
						)
					)
					(width 0)
					(fill yes)
				)
			)
		)
		(pad "2" smd custom
			(at 0 0.4445 270)
			(size 0.1397 0.1397)
			(layers "F.Cu" "F.Mask" "F.Paste")
			(net "GND")
			(options
				(clearance outline)
				(anchor circle)
			)
			(primitives
				(gr_poly
					(pts
						(arc
							(start -0.1778 -0.2794)
							(mid -0.249642 -0.249642)
							(end -0.2794 -0.1778)
						)
						(arc
							(start -0.2794 0.1778)
							(mid -0.249642 0.249642)
							(end -0.1778 0.2794)
						)
						(arc
							(start 0.1778 0.2794)
							(mid 0.249642 0.249642)
							(end 0.2794 0.1778)
						)
						(arc
							(start 0.2794 -0.1778)
							(mid 0.249642 -0.249642)
							(end 0.1778 -0.2794)
						)
					)
					(width 0)
					(fill yes)
				)
			)
		)
	)
	(footprint ""
		(layer "F.Cu")
		(at 36.9062 -147.447 180)
		(property "Reference" "PR115"
			(at 0 0 180)
			(layer "F.SilkS")
			(hide yes)
			(effects
				(font
					(size 1.27 1.27)
				)
			)
		)
		(property "Value" "20KR2F-L-GP"
			(at 0.064008 -3.993896 180)
			(unlocked yes)
			(layer "F.Fab")
			(hide yes)
			(effects
				(font
					(size 1.016 1.016)
					(thickness 0.1524)
				)
			)
		)
		(property "Device Type" "R402H16"
			(at 0.064008 -5.517896 180)
			(unlocked yes)
			(layer "F.Fab")
			(hide yes)
			(effects
				(font
					(size 1.016 1.016)
					(thickness 0.1524)
				)
			)
		)
		(duplicate_pad_numbers_are_jumpers no)
		(fp_line
			(start 0.508 -0.9398)
			(end -0.508 -0.9398)
			(stroke
				(width 0.1524)
				(type default)
			)
			(layer "F.SilkS")
		)
		(fp_line
			(start -0.508 -0.9398)
			(end -0.508 0.9398)
			(stroke
				(width 0.1524)
				(type default)
			)
			(layer "F.SilkS")
		)
		(fp_rect
			(start -0.508 0.9398)
			(end 0.508 -0.9398)
			(stroke
				(width 0)
				(type default)
			)
			(fill no)
			(layer "F.CrtYd")
		)
		(fp_rect
			(start -0.508 0.9398)
			(end 0.508 -0.9398)
			(stroke
				(width 0)
				(type default)
			)
			(fill no)
			(layer "F.Fab")
		)
		(pad "1" smd custom
			(at 0 -0.4445 180)
			(size 0.1397 0.1397)
			(layers "F.Cu" "F.Mask" "F.Paste")
			(net "P12VL_2490_PROG")
			(options
				(clearance outline)
				(anchor circle)
			)
			(primitives
				(gr_poly
					(pts
						(arc
							(start -0.1778 -0.2794)
							(mid -0.249642 -0.249642)
							(end -0.2794 -0.1778)
						)
						(arc
							(start -0.2794 0.1778)
							(mid -0.249642 0.249642)
							(end -0.1778 0.2794)
						)
						(arc
							(start 0.1778 0.2794)
							(mid 0.249642 0.249642)
							(end 0.2794 0.1778)
						)
						(arc
							(start 0.2794 -0.1778)
							(mid 0.249642 -0.249642)
							(end 0.1778 -0.2794)
						)
					)
					(width 0)
					(fill yes)
				)
			)
		)
		(pad "2" smd custom
			(at 0 0.4445 180)
			(size 0.1397 0.1397)
			(layers "F.Cu" "F.Mask" "F.Paste")
			(net "GND")
			(options
				(clearance outline)
				(anchor circle)
			)
			(primitives
				(gr_poly
					(pts
						(arc
							(start -0.1778 -0.2794)
							(mid -0.249642 -0.249642)
							(end -0.2794 -0.1778)
						)
						(arc
							(start -0.2794 0.1778)
							(mid -0.249642 0.249642)
							(end -0.1778 0.2794)
						)
						(arc
							(start 0.1778 0.2794)
							(mid 0.249642 0.249642)
							(end 0.2794 0.1778)
						)
						(arc
							(start 0.2794 -0.1778)
							(mid 0.249642 -0.249642)
							(end 0.1778 -0.2794)
						)
					)
					(width 0)
					(fill yes)
				)
			)
		)
	)
	(footprint ""
		(layer "F.Cu")
		(at 38.43909 -161.068766 180)
		(property "Reference" "R5"
			(at 0 0 180)
			(layer "F.SilkS")
			(hide yes)
			(effects
				(font
					(size 1.27 1.27)
				)
			)
		)
		(property "Value" "0R2J-2-GP"
			(at 0.064008 -3.993896 180)
			(unlocked yes)
			(layer "F.Fab")
			(hide yes)
			(effects
				(font
					(size 1.016 1.016)
					(thickness 0.1524)
				)
			)
		)
		(property "Device Type" "R402H16"
			(at 0.064008 -5.517896 180)
			(unlocked yes)
			(layer "F.Fab")
			(hide yes)
			(effects
				(font
					(size 1.016 1.016)
					(thickness 0.1524)
				)
			)
		)
		(duplicate_pad_numbers_are_jumpers no)
		(fp_line
			(start 0.508 -0.9398)
			(end -0.508 -0.9398)
			(stroke
				(width 0.1524)
				(type default)
			)
			(layer "F.SilkS")
		)
		(fp_line
			(start -0.508 -0.9398)
			(end -0.508 0.9398)
			(stroke
				(width 0.1524)
				(type default)
			)
			(layer "F.SilkS")
		)
		(fp_rect
			(start -0.508 0.9398)
			(end 0.508 -0.9398)
			(stroke
				(width 0)
				(type default)
			)
			(fill no)
			(layer "F.CrtYd")
		)
		(fp_rect
			(start -0.508 0.9398)
			(end 0.508 -0.9398)
			(stroke
				(width 0)
				(type default)
			)
			(fill no)
			(layer "F.Fab")
		)
		(pad "1" smd custom
			(at 0 -0.4445 180)
			(size 0.1397 0.1397)
			(layers "F.Cu" "F.Mask" "F.Paste")
			(net "NCT7904_CLKIN")
			(options
				(clearance outline)
				(anchor circle)
			)
			(primitives
				(gr_poly
					(pts
						(arc
							(start -0.1778 -0.2794)
							(mid -0.249642 -0.249642)
							(end -0.2794 -0.1778)
						)
						(arc
							(start -0.2794 0.1778)
							(mid -0.249642 0.249642)
							(end -0.1778 0.2794)
						)
						(arc
							(start 0.1778 0.2794)
							(mid 0.249642 0.249642)
							(end 0.2794 0.1778)
						)
						(arc
							(start 0.2794 -0.1778)
							(mid 0.249642 -0.249642)
							(end 0.1778 -0.2794)
						)
					)
					(width 0)
					(fill yes)
				)
			)
		)
		(pad "2" smd custom
			(at 0 0.4445 180)
			(size 0.1397 0.1397)
			(layers "F.Cu" "F.Mask" "F.Paste")
			(net "NCT7904_CLK")
			(options
				(clearance outline)
				(anchor circle)
			)
			(primitives
				(gr_poly
					(pts
						(arc
							(start -0.1778 -0.2794)
							(mid -0.249642 -0.249642)
							(end -0.2794 -0.1778)
						)
						(arc
							(start -0.2794 0.1778)
							(mid -0.249642 0.249642)
							(end -0.1778 0.2794)
						)
						(arc
							(start 0.1778 0.2794)
							(mid 0.249642 0.249642)
							(end 0.2794 0.1778)
						)
						(arc
							(start 0.2794 -0.1778)
							(mid 0.249642 -0.249642)
							(end 0.1778 -0.2794)
						)
					)
					(width 0)
					(fill yes)
				)
			)
		)
	)
	(footprint ""
		(layer "F.Cu")
		(at 31.9024 -91.8972 90)
		(property "Reference" "D16"
			(at 0 0 90)
			(layer "F.SilkS")
			(hide yes)
			(effects
				(font
					(size 1.27 1.27)
				)
			)
		)
		(property "Value" "MBRS340T3G-GP"
			(at 0 -10.6172 90)
			(unlocked yes)
			(layer "F.Fab")
			(hide yes)
			(effects
				(font
					(size 1.016 1.016)
					(thickness 0.1524)
				)
			)
		)
		(property "Device Type" "D8059AKH101"
			(at 0 -12.1412 90)
			(unlocked yes)
			(layer "F.Fab")
			(hide yes)
			(effects
				(font
					(size 1.016 1.016)
					(thickness 0.1524)
				)
			)
		)
		(duplicate_pad_numbers_are_jumpers no)
		(fp_line
			(start 3.175 -5.1054)
			(end 3.175 5.1054)
			(stroke
				(width 0.1524)
				(type default)
			)
			(layer "F.SilkS")
		)
		(fp_line
			(start -3.175 -5.1054)
			(end 3.175 -5.1054)
			(stroke
				(width 0.1524)
				(type default)
			)
			(layer "F.SilkS")
		)
		(fp_line
			(start 3.175 5.1054)
			(end -3.175 5.1054)
			(stroke
				(width 0.1524)
				(type default)
			)
			(layer "F.SilkS")
		)
		(fp_line
			(start -3.175 5.1054)
			(end -3.175 -5.1054)
			(stroke
				(width 0.1524)
				(type default)
			)
			(layer "F.SilkS")
		)
		(fp_line
			(start 3.175 5.2832)
			(end -3.175 5.2832)
			(stroke
				(width 0.508)
				(type default)
			)
			(layer "F.SilkS")
		)
		(fp_rect
			(start -3.429 5.1816)
			(end 3.429 -5.1816)
			(stroke
				(width 0)
				(type default)
			)
			(fill no)
			(layer "F.CrtYd")
		)
		(fp_poly
			(pts
				(xy -3.429 -5.1816) (xy 3.429 -5.1816) (xy 3.429 5.1816) (xy -3.429 5.1816)
			)
			(stroke
				(width 0)
				(type default)
			)
			(fill no)
			(layer "F.Fab")
		)
		(pad "A" smd rect
			(at 0 -3.77571 90)
			(size 3.2512 2.159)
			(layers "F.Cu" "F.Mask" "F.Paste")
			(net "GND")
		)
		(pad "K" smd rect
			(at 0 3.77571 90)
			(size 3.2512 2.159)
			(layers "F.Cu" "F.Mask" "F.Paste")
			(net "P12VL")
		)
	)
	(footprint ""
		(layer "F.Cu")
		(at 42.5958 -177.2666 180)
		(property "Reference" "PR47"
			(at 0 0 180)
			(layer "F.SilkS")
			(hide yes)
			(effects
				(font
					(size 1.27 1.27)
				)
			)
		)
		(property "Value" "4K7R2J-2-GP"
			(at 0.064008 -3.993896 180)
			(unlocked yes)
			(layer "F.Fab")
			(hide yes)
			(effects
				(font
					(size 1.016 1.016)
					(thickness 0.1524)
				)
			)
		)
		(property "Device Type" "R402H16"
			(at 0.064008 -5.517896 180)
			(unlocked yes)
			(layer "F.Fab")
			(hide yes)
			(effects
				(font
					(size 1.016 1.016)
					(thickness 0.1524)
				)
			)
		)
		(duplicate_pad_numbers_are_jumpers no)
		(fp_line
			(start 0.508 -0.9398)
			(end -0.508 -0.9398)
			(stroke
				(width 0.1524)
				(type default)
			)
			(layer "F.SilkS")
		)
		(fp_line
			(start -0.508 -0.9398)
			(end -0.508 0.9398)
			(stroke
				(width 0.1524)
				(type default)
			)
			(layer "F.SilkS")
		)
		(fp_rect
			(start -0.508 0.9398)
			(end 0.508 -0.9398)
			(stroke
				(width 0)
				(type default)
			)
			(fill no)
			(layer "F.CrtYd")
		)
		(fp_rect
			(start -0.508 0.9398)
			(end 0.508 -0.9398)
			(stroke
				(width 0)
				(type default)
			)
			(fill no)
			(layer "F.Fab")
		)
		(pad "1" smd custom
			(at 0 -0.4445 180)
			(size 0.1397 0.1397)
			(layers "F.Cu" "F.Mask" "F.Paste")
			(net "P3V3_AUX")
			(options
				(clearance outline)
				(anchor circle)
			)
			(primitives
				(gr_poly
					(pts
						(arc
							(start -0.1778 -0.2794)
							(mid -0.249642 -0.249642)
							(end -0.2794 -0.1778)
						)
						(arc
							(start -0.2794 0.1778)
							(mid -0.249642 0.249642)
							(end -0.1778 0.2794)
						)
						(arc
							(start 0.1778 0.2794)
							(mid 0.249642 0.249642)
							(end 0.2794 0.1778)
						)
						(arc
							(start 0.2794 -0.1778)
							(mid 0.249642 -0.249642)
							(end 0.1778 -0.2794)
						)
					)
					(width 0)
					(fill yes)
				)
			)
		)
		(pad "2" smd custom
			(at 0 0.4445 180)
			(size 0.1397 0.1397)
			(layers "F.Cu" "F.Mask" "F.Paste")
			(net "D_LATCH_Q")
			(options
				(clearance outline)
				(anchor circle)
			)
			(primitives
				(gr_poly
					(pts
						(arc
							(start -0.1778 -0.2794)
							(mid -0.249642 -0.249642)
							(end -0.2794 -0.1778)
						)
						(arc
							(start -0.2794 0.1778)
							(mid -0.249642 0.249642)
							(end -0.1778 0.2794)
						)
						(arc
							(start 0.1778 0.2794)
							(mid 0.249642 0.249642)
							(end 0.2794 0.1778)
						)
						(arc
							(start 0.2794 -0.1778)
							(mid 0.249642 -0.249642)
							(end 0.1778 -0.2794)
						)
					)
					(width 0)
					(fill yes)
				)
			)
		)
	)
	(footprint ""
		(layer "F.Cu")
		(at 37.719 -352.425 90)
		(property "Reference" "C261"
			(at 0 0 90)
			(layer "F.SilkS")
			(hide yes)
			(effects
				(font
					(size 1.27 1.27)
				)
			)
		)
		(property "Value" "SC10U25V6KX-1GP"
			(at -0.0762 -5.1308 90)
			(unlocked yes)
			(layer "F.Fab")
			(hide yes)
			(effects
				(font
					(size 1.016 1.016)
					(thickness 0.1524)
				)
			)
		)
		(property "Device Type" "C1206H71"
			(at -0.127 -6.6548 90)
			(unlocked yes)
			(layer "F.Fab")
			(hide yes)
			(effects
				(font
					(size 1.016 1.016)
					(thickness 0.1524)
				)
			)
		)
		(duplicate_pad_numbers_are_jumpers no)
		(fp_line
			(start 1.016 -2.2352)
			(end 1.016 -0.8382)
			(stroke
				(width 0.1524)
				(type default)
			)
			(layer "F.SilkS")
		)
		(fp_line
			(start -1.016 -2.2352)
			(end 1.016 -2.2352)
			(stroke
				(width 0.1524)
				(type default)
			)
			(layer "F.SilkS")
		)
		(fp_line
			(start -1.016 -0.8382)
			(end -1.016 -2.2352)
			(stroke
				(width 0.1524)
				(type default)
			)
			(layer "F.SilkS")
		)
		(fp_line
			(start 1.016 0.8382)
			(end 1.016 2.2352)
			(stroke
				(width 0.1524)
				(type default)
			)
			(layer "F.SilkS")
		)
		(fp_line
			(start 1.016 2.2352)
			(end -1.016 2.2352)
			(stroke
				(width 0.1524)
				(type default)
			)
			(layer "F.SilkS")
		)
		(fp_line
			(start -1.016 2.2352)
			(end -1.016 0.8382)
			(stroke
				(width 0.1524)
				(type default)
			)
			(layer "F.SilkS")
		)
		(fp_rect
			(start -1.0922 2.3114)
			(end 1.0922 -2.3114)
			(stroke
				(width 0)
				(type default)
			)
			(fill no)
			(layer "F.CrtYd")
		)
		(fp_poly
			(pts
				(xy 1.0922 -2.3114) (xy 1.0922 2.3114) (xy -1.0922 2.3114) (xy -1.0922 -2.3114)
			)
			(stroke
				(width 0)
				(type default)
			)
			(fill no)
			(layer "F.Fab")
		)
		(pad "1" smd rect
			(at 0 -1.397 90)
			(size 1.651 1.27)
			(layers "F.Cu" "F.Mask" "F.Paste")
			(net "OTP_RETRY_G")
		)
		(pad "2" smd rect
			(at 0 1.397 90)
			(size 1.651 1.27)
			(layers "F.Cu" "F.Mask" "F.Paste")
			(net "GND")
		)
	)
	(footprint ""
		(layer "F.Cu")
		(at 15.9258 -146.6088 90)
		(property "Reference" "R68"
			(at 0 0 90)
			(layer "F.SilkS")
			(hide yes)
			(effects
				(font
					(size 1.27 1.27)
				)
			)
		)
		(property "Value" "4K7R2F-GP"
			(at 0.064008 -3.993896 90)
			(unlocked yes)
			(layer "F.Fab")
			(hide yes)
			(effects
				(font
					(size 1.016 1.016)
					(thickness 0.1524)
				)
			)
		)
		(property "Device Type" "R402H16"
			(at 0.064008 -5.517896 90)
			(unlocked yes)
			(layer "F.Fab")
			(hide yes)
			(effects
				(font
					(size 1.016 1.016)
					(thickness 0.1524)
				)
			)
		)
		(duplicate_pad_numbers_are_jumpers no)
		(fp_line
			(start -0.508 -0.9398)
			(end -1.524 -0.9398)
			(stroke
				(width 0.1524)
				(type default)
			)
			(layer "F.SilkS")
		)
		(fp_line
			(start -1.524 -0.9398)
			(end -1.524 0.9398)
			(stroke
				(width 0.1524)
				(type default)
			)
			(layer "F.SilkS")
		)
		(fp_rect
			(start -0.508 0.9398)
			(end 0.508 -0.9398)
			(stroke
				(width 0)
				(type default)
			)
			(fill no)
			(layer "F.CrtYd")
		)
		(fp_rect
			(start -0.508 0.9398)
			(end 0.508 -0.9398)
			(stroke
				(width 0)
				(type default)
			)
			(fill no)
			(layer "F.Fab")
		)
		(pad "1" smd custom
			(at 0 -0.4445 90)
			(size 0.1397 0.1397)
			(layers "F.Cu" "F.Mask" "F.Paste")
			(net "P12V")
			(options
				(clearance outline)
				(anchor circle)
			)
			(primitives
				(gr_poly
					(pts
						(arc
							(start -0.1778 -0.2794)
							(mid -0.249642 -0.249642)
							(end -0.2794 -0.1778)
						)
						(arc
							(start -0.2794 0.1778)
							(mid -0.249642 0.249642)
							(end -0.1778 0.2794)
						)
						(arc
							(start 0.1778 0.2794)
							(mid 0.249642 0.249642)
							(end 0.2794 0.1778)
						)
						(arc
							(start 0.2794 -0.1778)
							(mid 0.249642 -0.249642)
							(end 0.1778 -0.2794)
						)
					)
					(width 0)
					(fill yes)
				)
			)
		)
		(pad "2" smd custom
			(at 0 0.4445 90)
			(size 0.1397 0.1397)
			(layers "F.Cu" "F.Mask" "F.Paste")
			(net "FAN_TACH9")
			(options
				(clearance outline)
				(anchor circle)
			)
			(primitives
				(gr_poly
					(pts
						(arc
							(start -0.1778 -0.2794)
							(mid -0.249642 -0.249642)
							(end -0.2794 -0.1778)
						)
						(arc
							(start -0.2794 0.1778)
							(mid -0.249642 0.249642)
							(end -0.1778 0.2794)
						)
						(arc
							(start 0.1778 0.2794)
							(mid 0.249642 0.249642)
							(end 0.2794 0.1778)
						)
						(arc
							(start 0.2794 -0.1778)
							(mid 0.249642 -0.249642)
							(end 0.1778 -0.2794)
						)
					)
					(width 0)
					(fill yes)
				)
			)
		)
	)
	(footprint ""
		(layer "F.Cu")
		(at 15.494 -167.0304 90)
		(property "Reference" "C33"
			(at 0 0 90)
			(layer "F.SilkS")
			(hide yes)
			(effects
				(font
					(size 1.27 1.27)
				)
			)
		)
		(property "Value" "SCD1U50V3KX-GP"
			(at 0 -2.8194 90)
			(unlocked yes)
			(layer "F.Fab")
			(hide yes)
			(effects
				(font
					(size 1.016 1.016)
					(thickness 0.1524)
				)
			)
		)
		(property "Device Type" "C603H36"
			(at 0 -4.3434 90)
			(unlocked yes)
			(layer "F.Fab")
			(hide yes)
			(effects
				(font
					(size 1.016 1.016)
					(thickness 0.1524)
				)
			)
		)
		(duplicate_pad_numbers_are_jumpers no)
		(fp_line
			(start 0.508 0)
			(end -0.508 0)
			(stroke
				(width 0.2032)
				(type default)
			)
			(layer "F.SilkS")
		)
		(fp_rect
			(start -0.5842 1.3335)
			(end 0.5842 -1.3335)
			(stroke
				(width 0)
				(type default)
			)
			(fill no)
			(layer "F.CrtYd")
		)
		(fp_rect
			(start -0.5842 1.3335)
			(end 0.5842 -1.3335)
			(stroke
				(width 0)
				(type default)
			)
			(fill no)
			(layer "F.Fab")
		)
		(pad "1" smd custom
			(at 0 -0.762 90)
			(size 0.2159 0.2159)
			(layers "F.Cu" "F.Mask" "F.Paste")
			(net "P12V")
			(options
				(clearance outline)
				(anchor circle)
			)
			(primitives
				(gr_poly
					(pts
						(arc
							(start -0.3302 -0.4318)
							(mid -0.402042 -0.402042)
							(end -0.4318 -0.3302)
						)
						(arc
							(start -0.4318 0.3302)
							(mid -0.402042 0.402042)
							(end -0.3302 0.4318)
						)
						(arc
							(start 0.3302 0.4318)
							(mid 0.402042 0.402042)
							(end 0.4318 0.3302)
						)
						(arc
							(start 0.4318 -0.3302)
							(mid 0.402042 -0.402042)
							(end 0.3302 -0.4318)
						)
					)
					(width 0)
					(fill yes)
				)
			)
		)
		(pad "2" smd custom
			(at 0 0.762 90)
			(size 0.2159 0.2159)
			(layers "F.Cu" "F.Mask" "F.Paste")
			(net "GND")
			(options
				(clearance outline)
				(anchor circle)
			)
			(primitives
				(gr_poly
					(pts
						(arc
							(start -0.3302 -0.4318)
							(mid -0.402042 -0.402042)
							(end -0.4318 -0.3302)
						)
						(arc
							(start -0.4318 0.3302)
							(mid -0.402042 0.402042)
							(end -0.3302 0.4318)
						)
						(arc
							(start 0.3302 0.4318)
							(mid 0.402042 0.402042)
							(end 0.4318 0.3302)
						)
						(arc
							(start 0.4318 -0.3302)
							(mid 0.402042 -0.402042)
							(end 0.3302 -0.4318)
						)
					)
					(width 0)
					(fill yes)
				)
			)
		)
	)
)
